(kicad_pcb
	(version 20260206)
	(generator "pcbnew")
	(generator_version "10.0")
	(general
		(thickness 1.6)
		(legacy_teardrops no)
	)
	(paper "A4")
	(title_block
		(title "04192023_DAF0TMB3IC0_F0TG_MB_C_brd_V02_OCP.brd")
		(comment 1 "Grand Teton / footprints 7458-7465 of 8354")
	)
	(layers
		(0 "F.Cu" signal "TOP")
		(4 "In1.Cu" signal "GND")
		(6 "In2.Cu" signal "IN1")
		(8 "In3.Cu" signal "GND1")
		(10 "In4.Cu" signal "IN2")
		(12 "In5.Cu" signal "GND2")
		(14 "In6.Cu" signal "IN3")
		(16 "In7.Cu" signal "GND3")
		(18 "In8.Cu" signal "VCC")
		(20 "In9.Cu" signal "VCC1")
		(22 "In10.Cu" signal "GND4")
		(24 "In11.Cu" signal "IN4")
		(26 "In12.Cu" signal "GND5")
		(28 "In13.Cu" signal "IN5")
		(30 "In14.Cu" signal "GND6")
		(32 "In15.Cu" signal "IN6")
		(34 "In16.Cu" signal "GND7")
		(2 "B.Cu" signal "BOTTOM")
		(9 "F.Adhes" user "F.Adhesive")
		(11 "B.Adhes" user "B.Adhesive")
		(13 "F.Paste" user "Package Geometry/Pastemask Top")
		(15 "B.Paste" user "Package Geometry/Pastemask Bottom")
		(5 "F.SilkS" user "Ref Des/Silkscreen Top")
		(7 "B.SilkS" user "Ref Des/Silkscreen Bottom")
		(1 "F.Mask" user "Board Geometry/Soldermask Top")
		(3 "B.Mask" user "Board Geometry/Soldermask Bottom")
		(17 "Dwgs.User" user "User.Drawings")
		(19 "Cmts.User" user "User.Comments")
		(21 "Eco1.User" user "User.Eco1")
		(23 "Eco2.User" user "User.Eco2")
		(25 "Edge.Cuts" user "Board Geometry/Outline")
		(27 "Margin" user)
		(31 "F.CrtYd" user "Package Geometry/Place Bound Top")
		(29 "B.CrtYd" user "Package Geometry/Place Bound Bottom")
		(35 "F.Fab" user "Ref Des/Assembly Top")
		(33 "B.Fab" user "Ref Des/Assembly Bottom")
	)
	(footprint ""
		(layer "B.Cu")
		(at 125.389386 -259.73024)
		(property "Reference" "C2462"
			(at 0 0 0)
			(layer "B.SilkS")
			(hide yes)
			(effects
				(font
					(size 1.27 1.27)
				)
				(justify mirror)
			)
		)
		(property "Value" ""
			(at 0 0 0)
			(layer "B.Fab")
			(effects
				(font
					(size 1.27 1.27)
				)
				(justify mirror)
			)
		)
		(duplicate_pad_numbers_are_jumpers no)
		(fp_line
			(start -0.7874 -0.4064)
			(end -0.7874 0.4064)
			(stroke
				(width 0.1524)
				(type default)
			)
			(layer "B.SilkS")
		)
		(fp_line
			(start -0.7874 0.4064)
			(end 0.7874 0.4064)
			(stroke
				(width 0.1524)
				(type default)
			)
			(layer "B.SilkS")
		)
		(fp_line
			(start 0.7874 -0.4064)
			(end -0.7874 -0.4064)
			(stroke
				(width 0.1524)
				(type default)
			)
			(layer "B.SilkS")
		)
		(fp_line
			(start 0.7874 0.4064)
			(end 0.7874 -0.4064)
			(stroke
				(width 0.1524)
				(type default)
			)
			(layer "B.SilkS")
		)
		(fp_line
			(start -0.67945 -0.3048)
			(end -0.67945 0.3048)
			(stroke
				(width 0.1)
				(type default)
			)
			(layer "B.Fab")
		)
		(fp_line
			(start -0.67945 0.3048)
			(end -0.120396 0.3048)
			(stroke
				(width 0.1)
				(type default)
			)
			(layer "B.Fab")
		)
		(fp_line
			(start -0.12065 -0.3048)
			(end -0.67945 -0.3048)
			(stroke
				(width 0.1)
				(type default)
			)
			(layer "B.Fab")
		)
		(fp_line
			(start -0.12065 -0.2794)
			(end -0.12065 -0.3048)
			(stroke
				(width 0.1)
				(type default)
			)
			(layer "B.Fab")
		)
		(fp_line
			(start -0.120396 0.2794)
			(end 0.12065 0.2794)
			(stroke
				(width 0.1)
				(type default)
			)
			(layer "B.Fab")
		)
		(fp_line
			(start -0.120396 0.3048)
			(end -0.120396 0.2794)
			(stroke
				(width 0.1)
				(type default)
			)
			(layer "B.Fab")
		)
		(fp_line
			(start 0.12065 -0.305054)
			(end 0.12065 -0.2794)
			(stroke
				(width 0.1)
				(type default)
			)
			(layer "B.Fab")
		)
		(fp_line
			(start 0.12065 -0.2794)
			(end -0.12065 -0.2794)
			(stroke
				(width 0.1)
				(type default)
			)
			(layer "B.Fab")
		)
		(fp_line
			(start 0.12065 0.2794)
			(end 0.12065 0.3048)
			(stroke
				(width 0.1)
				(type default)
			)
			(layer "B.Fab")
		)
		(fp_line
			(start 0.12065 0.3048)
			(end 0.67945 0.3048)
			(stroke
				(width 0.1)
				(type default)
			)
			(layer "B.Fab")
		)
		(fp_line
			(start 0.67945 -0.305054)
			(end 0.12065 -0.305054)
			(stroke
				(width 0.1)
				(type default)
			)
			(layer "B.Fab")
		)
		(fp_line
			(start 0.67945 0.3048)
			(end 0.67945 -0.305054)
			(stroke
				(width 0.1)
				(type default)
			)
			(layer "B.Fab")
		)
		(pad "1" smd circle
			(at 0.40005 0 180)
			(size 0 0)
			(layers "B.Cu" "B.Mask" "B.Paste")
			(net "PVDDCR_SOC_P1")
		)
		(pad "2" smd circle
			(at -0.40005 0 180)
			(size 0 0)
			(layers "B.Cu" "B.Mask" "B.Paste")
			(net "GND")
		)
	)
	(footprint ""
		(layer "B.Cu")
		(at 415.285682 -416.899344 90)
		(property "Reference" "C6626"
			(at 0 0 90)
			(layer "B.SilkS")
			(hide yes)
			(effects
				(font
					(size 1.27 1.27)
				)
				(justify mirror)
			)
		)
		(property "Value" ""
			(at 0 0 90)
			(layer "B.Fab")
			(effects
				(font
					(size 1.27 1.27)
				)
				(justify mirror)
			)
		)
		(duplicate_pad_numbers_are_jumpers no)
		(fp_line
			(start 0.299974 -0.150114)
			(end -0.299974 -0.150114)
			(stroke
				(width 0.1)
				(type default)
			)
			(layer "B.Fab")
		)
		(fp_line
			(start -0.299974 -0.150114)
			(end -0.299974 0.150114)
			(stroke
				(width 0.1)
				(type default)
			)
			(layer "B.Fab")
		)
		(fp_line
			(start 0.299974 0.150114)
			(end 0.299974 -0.150114)
			(stroke
				(width 0.1)
				(type default)
			)
			(layer "B.Fab")
		)
		(fp_line
			(start -0.299974 0.150114)
			(end 0.299974 0.150114)
			(stroke
				(width 0.1)
				(type default)
			)
			(layer "B.Fab")
		)
		(pad "1" smd rect
			(at 0.2667 0 270)
			(size 0.3048 0.381)
			(layers "B.Cu" "B.Mask" "B.Paste")
			(net "P5E_CPU0_P3_TX_BUF_C_DN<14>")
		)
		(pad "2" smd rect
			(at -0.2667 0 270)
			(size 0.3048 0.381)
			(layers "B.Cu" "B.Mask" "B.Paste")
			(net "P5E_CPU0_P3_TX_BUF_DN<14>")
		)
	)
	(footprint ""
		(layer "B.Cu")
		(at 102.780084 -384.575558)
		(property "Reference" "L5"
			(at 0 0 0)
			(layer "B.SilkS")
			(hide yes)
			(effects
				(font
					(size 1.27 1.27)
				)
				(justify mirror)
			)
		)
		(property "Value" ""
			(at 0 0 0)
			(layer "B.Fab")
			(effects
				(font
					(size 1.27 1.27)
				)
				(justify mirror)
			)
		)
		(duplicate_pad_numbers_are_jumpers no)
		(fp_line
			(start -1.63576 -0.8128)
			(end -1.63576 0.8128)
			(stroke
				(width 0.1524)
				(type default)
			)
			(layer "B.SilkS")
		)
		(fp_line
			(start -1.63576 0.8128)
			(end 1.63576 0.8128)
			(stroke
				(width 0.1524)
				(type default)
			)
			(layer "B.SilkS")
		)
		(fp_line
			(start 1.63576 -0.8128)
			(end -1.63576 -0.8128)
			(stroke
				(width 0.1524)
				(type default)
			)
			(layer "B.SilkS")
		)
		(fp_line
			(start 1.63576 -0.8128)
			(end 1.63576 0.8128)
			(stroke
				(width 0.1524)
				(type default)
			)
			(layer "B.SilkS")
		)
		(fp_line
			(start -1.560576 -0.738632)
			(end 1.56083 -0.738632)
			(stroke
				(width 0.1)
				(type default)
			)
			(layer "B.Fab")
		)
		(fp_line
			(start -1.560576 0.7366)
			(end -1.560576 -0.738632)
			(stroke
				(width 0.1)
				(type default)
			)
			(layer "B.Fab")
		)
		(fp_line
			(start -1.524 0.7366)
			(end -1.560576 0.7366)
			(stroke
				(width 0.1)
				(type default)
			)
			(layer "B.Fab")
		)
		(fp_line
			(start 1.524 0.7366)
			(end -1.524 0.7366)
			(stroke
				(width 0.1)
				(type default)
			)
			(layer "B.Fab")
		)
		(fp_line
			(start 1.56083 -0.738632)
			(end 1.56083 0.7366)
			(stroke
				(width 0.1)
				(type default)
			)
			(layer "B.Fab")
		)
		(fp_line
			(start 1.56083 0.7366)
			(end 1.524 0.7366)
			(stroke
				(width 0.1)
				(type default)
			)
			(layer "B.Fab")
		)
		(pad "1" smd rect
			(at 0.94996 0)
			(size 1.1176 1.3716)
			(layers "B.Cu" "B.Mask" "B.Paste")
			(net "P1V8_CPU1_RT_1D")
		)
		(pad "2" smd rect
			(at -0.94996 0)
			(size 1.1176 1.3716)
			(layers "B.Cu" "B.Mask" "B.Paste")
			(net "P1V8_CPU1_RT1_1A")
		)
	)
	(footprint ""
		(layer "B.Cu")
		(at 80.046322 -388.011162 -90)
		(property "Reference" "C341"
			(at 0 0 90)
			(layer "B.SilkS")
			(hide yes)
			(effects
				(font
					(size 1.27 1.27)
				)
				(justify mirror)
			)
		)
		(property "Value" ""
			(at 0 0 90)
			(layer "B.Fab")
			(effects
				(font
					(size 1.27 1.27)
				)
				(justify mirror)
			)
		)
		(duplicate_pad_numbers_are_jumpers no)
		(fp_line
			(start -0.299974 0.150114)
			(end 0.299974 0.150114)
			(stroke
				(width 0.1)
				(type default)
			)
			(layer "B.Fab")
		)
		(fp_line
			(start 0.299974 0.150114)
			(end 0.299974 -0.150114)
			(stroke
				(width 0.1)
				(type default)
			)
			(layer "B.Fab")
		)
		(fp_line
			(start -0.299974 -0.150114)
			(end -0.299974 0.150114)
			(stroke
				(width 0.1)
				(type default)
			)
			(layer "B.Fab")
		)
		(fp_line
			(start 0.299974 -0.150114)
			(end -0.299974 -0.150114)
			(stroke
				(width 0.1)
				(type default)
			)
			(layer "B.Fab")
		)
		(pad "1" smd rect
			(at 0.2667 0 90)
			(size 0.3048 0.381)
			(layers "B.Cu" "B.Mask" "B.Paste")
			(net "P0V9_CPU1_RT1_2A")
		)
		(pad "2" smd rect
			(at -0.2667 0 90)
			(size 0.3048 0.381)
			(layers "B.Cu" "B.Mask" "B.Paste")
			(net "GND")
		)
	)
	(footprint ""
		(layer "B.Cu")
		(at 117.895624 -262.205216)
		(property "Reference" "C2492"
			(at 0 0 0)
			(layer "B.SilkS")
			(hide yes)
			(effects
				(font
					(size 1.27 1.27)
				)
				(justify mirror)
			)
		)
		(property "Value" ""
			(at 0 0 0)
			(layer "B.Fab")
			(effects
				(font
					(size 1.27 1.27)
				)
				(justify mirror)
			)
		)
		(duplicate_pad_numbers_are_jumpers no)
		(fp_line
			(start -0.7874 -0.4064)
			(end -0.7874 0.4064)
			(stroke
				(width 0.1524)
				(type default)
			)
			(layer "B.SilkS")
		)
		(fp_line
			(start -0.7874 0.4064)
			(end 0.7874 0.4064)
			(stroke
				(width 0.1524)
				(type default)
			)
			(layer "B.SilkS")
		)
		(fp_line
			(start 0.7874 -0.4064)
			(end -0.7874 -0.4064)
			(stroke
				(width 0.1524)
				(type default)
			)
			(layer "B.SilkS")
		)
		(fp_line
			(start 0.7874 0.4064)
			(end 0.7874 -0.4064)
			(stroke
				(width 0.1524)
				(type default)
			)
			(layer "B.SilkS")
		)
		(fp_line
			(start -0.67945 -0.3048)
			(end -0.67945 0.3048)
			(stroke
				(width 0.1)
				(type default)
			)
			(layer "B.Fab")
		)
		(fp_line
			(start -0.67945 0.3048)
			(end -0.120396 0.3048)
			(stroke
				(width 0.1)
				(type default)
			)
			(layer "B.Fab")
		)
		(fp_line
			(start -0.12065 -0.3048)
			(end -0.67945 -0.3048)
			(stroke
				(width 0.1)
				(type default)
			)
			(layer "B.Fab")
		)
		(fp_line
			(start -0.12065 -0.2794)
			(end -0.12065 -0.3048)
			(stroke
				(width 0.1)
				(type default)
			)
			(layer "B.Fab")
		)
		(fp_line
			(start -0.120396 0.2794)
			(end 0.12065 0.2794)
			(stroke
				(width 0.1)
				(type default)
			)
			(layer "B.Fab")
		)
		(fp_line
			(start -0.120396 0.3048)
			(end -0.120396 0.2794)
			(stroke
				(width 0.1)
				(type default)
			)
			(layer "B.Fab")
		)
		(fp_line
			(start 0.12065 -0.305054)
			(end 0.12065 -0.2794)
			(stroke
				(width 0.1)
				(type default)
			)
			(layer "B.Fab")
		)
		(fp_line
			(start 0.12065 -0.2794)
			(end -0.12065 -0.2794)
			(stroke
				(width 0.1)
				(type default)
			)
			(layer "B.Fab")
		)
		(fp_line
			(start 0.12065 0.2794)
			(end 0.12065 0.3048)
			(stroke
				(width 0.1)
				(type default)
			)
			(layer "B.Fab")
		)
		(fp_line
			(start 0.12065 0.3048)
			(end 0.67945 0.3048)
			(stroke
				(width 0.1)
				(type default)
			)
			(layer "B.Fab")
		)
		(fp_line
			(start 0.67945 -0.305054)
			(end 0.12065 -0.305054)
			(stroke
				(width 0.1)
				(type default)
			)
			(layer "B.Fab")
		)
		(fp_line
			(start 0.67945 0.3048)
			(end 0.67945 -0.305054)
			(stroke
				(width 0.1)
				(type default)
			)
			(layer "B.Fab")
		)
		(pad "1" smd circle
			(at 0.40005 0 180)
			(size 0 0)
			(layers "B.Cu" "B.Mask" "B.Paste")
			(net "PVDD11_S3_P1")
		)
		(pad "2" smd circle
			(at -0.40005 0 180)
			(size 0 0)
			(layers "B.Cu" "B.Mask" "B.Paste")
			(net "GND")
		)
	)
	(footprint ""
		(layer "B.Cu")
		(at 97.853754 -178.886612 90)
		(property "Reference" "PC294_3"
			(at 0 0 90)
			(layer "B.SilkS")
			(hide yes)
			(effects
				(font
					(size 1.27 1.27)
				)
				(justify mirror)
			)
		)
		(property "Value" ""
			(at 0 0 90)
			(layer "B.Fab")
			(effects
				(font
					(size 1.27 1.27)
				)
				(justify mirror)
			)
		)
		(duplicate_pad_numbers_are_jumpers no)
		(fp_line
			(start 1.524 -0.762)
			(end -1.524 -0.762)
			(stroke
				(width 0.1524)
				(type default)
			)
			(layer "B.SilkS")
		)
		(fp_line
			(start -1.524 -0.762)
			(end -1.524 0.762)
			(stroke
				(width 0.1524)
				(type default)
			)
			(layer "B.SilkS")
		)
		(fp_line
			(start 1.524 0.762)
			(end 1.524 -0.762)
			(stroke
				(width 0.1524)
				(type default)
			)
			(layer "B.SilkS")
		)
		(fp_line
			(start -1.524 0.762)
			(end 1.524 0.762)
			(stroke
				(width 0.1524)
				(type default)
			)
			(layer "B.SilkS")
		)
		(fp_line
			(start 1.1049 -0.724916)
			(end 1.1049 0.724916)
			(stroke
				(width 0.1)
				(type default)
			)
			(layer "B.Fab")
		)
		(fp_line
			(start -1.1049 -0.724916)
			(end 1.1049 -0.724916)
			(stroke
				(width 0.1)
				(type default)
			)
			(layer "B.Fab")
		)
		(fp_line
			(start 1.1049 0.724916)
			(end -1.1049 0.724916)
			(stroke
				(width 0.1)
				(type default)
			)
			(layer "B.Fab")
		)
		(fp_line
			(start -1.1049 0.724916)
			(end -1.1049 -0.724916)
			(stroke
				(width 0.1)
				(type default)
			)
			(layer "B.Fab")
		)
		(pad "1" smd rect
			(at 0.889 0 90)
			(size 1.016 1.27)
			(layers "B.Cu" "B.Mask" "B.Paste")
			(net "SW_P12V_AUX_PVDDCR_CPU0_P1_FLT")
		)
		(pad "2" smd rect
			(at -0.889 0 90)
			(size 1.016 1.27)
			(layers "B.Cu" "B.Mask" "B.Paste")
			(net "GND")
		)
	)
	(footprint ""
		(layer "B.Cu")
		(at 102.656386 -264.354564)
		(property "Reference" "C2495"
			(at 0 0 0)
			(layer "B.SilkS")
			(hide yes)
			(effects
				(font
					(size 1.27 1.27)
				)
				(justify mirror)
			)
		)
		(property "Value" ""
			(at 0 0 0)
			(layer "B.Fab")
			(effects
				(font
					(size 1.27 1.27)
				)
				(justify mirror)
			)
		)
		(duplicate_pad_numbers_are_jumpers no)
		(fp_line
			(start -0.7874 -0.4064)
			(end -0.7874 0.4064)
			(stroke
				(width 0.1524)
				(type default)
			)
			(layer "B.SilkS")
		)
		(fp_line
			(start -0.7874 0.4064)
			(end 0.7874 0.4064)
			(stroke
				(width 0.1524)
				(type default)
			)
			(layer "B.SilkS")
		)
		(fp_line
			(start 0.7874 -0.4064)
			(end -0.7874 -0.4064)
			(stroke
				(width 0.1524)
				(type default)
			)
			(layer "B.SilkS")
		)
		(fp_line
			(start 0.7874 0.4064)
			(end 0.7874 -0.4064)
			(stroke
				(width 0.1524)
				(type default)
			)
			(layer "B.SilkS")
		)
		(fp_line
			(start -0.67945 -0.3048)
			(end -0.67945 0.3048)
			(stroke
				(width 0.1)
				(type default)
			)
			(layer "B.Fab")
		)
		(fp_line
			(start -0.67945 0.3048)
			(end -0.120396 0.3048)
			(stroke
				(width 0.1)
				(type default)
			)
			(layer "B.Fab")
		)
		(fp_line
			(start -0.12065 -0.3048)
			(end -0.67945 -0.3048)
			(stroke
				(width 0.1)
				(type default)
			)
			(layer "B.Fab")
		)
		(fp_line
			(start -0.12065 -0.2794)
			(end -0.12065 -0.3048)
			(stroke
				(width 0.1)
				(type default)
			)
			(layer "B.Fab")
		)
		(fp_line
			(start -0.120396 0.2794)
			(end 0.12065 0.2794)
			(stroke
				(width 0.1)
				(type default)
			)
			(layer "B.Fab")
		)
		(fp_line
			(start -0.120396 0.3048)
			(end -0.120396 0.2794)
			(stroke
				(width 0.1)
				(type default)
			)
			(layer "B.Fab")
		)
		(fp_line
			(start 0.12065 -0.305054)
			(end 0.12065 -0.2794)
			(stroke
				(width 0.1)
				(type default)
			)
			(layer "B.Fab")
		)
		(fp_line
			(start 0.12065 -0.2794)
			(end -0.12065 -0.2794)
			(stroke
				(width 0.1)
				(type default)
			)
			(layer "B.Fab")
		)
		(fp_line
			(start 0.12065 0.2794)
			(end 0.12065 0.3048)
			(stroke
				(width 0.1)
				(type default)
			)
			(layer "B.Fab")
		)
		(fp_line
			(start 0.12065 0.3048)
			(end 0.67945 0.3048)
			(stroke
				(width 0.1)
				(type default)
			)
			(layer "B.Fab")
		)
		(fp_line
			(start 0.67945 -0.305054)
			(end 0.12065 -0.305054)
			(stroke
				(width 0.1)
				(type default)
			)
			(layer "B.Fab")
		)
		(fp_line
			(start 0.67945 0.3048)
			(end 0.67945 -0.305054)
			(stroke
				(width 0.1)
				(type default)
			)
			(layer "B.Fab")
		)
		(pad "1" smd circle
			(at 0.40005 0 180)
			(size 0 0)
			(layers "B.Cu" "B.Mask" "B.Paste")
			(net "PVDD11_S3_P1")
		)
		(pad "2" smd circle
			(at -0.40005 0 180)
			(size 0 0)
			(layers "B.Cu" "B.Mask" "B.Paste")
			(net "GND")
		)
	)
	(footprint ""
		(layer "B.Cu")
		(at 350.204278 -254.507492 -60)
		(property "Reference" "C2561"
			(at 0 0 120)
			(layer "B.SilkS")
			(hide yes)
			(effects
				(font
					(size 1.27 1.27)
				)
				(justify mirror)
			)
		)
		(property "Value" ""
			(at 0 0 120)
			(layer "B.Fab")
			(effects
				(font
					(size 1.27 1.27)
				)
				(justify mirror)
			)
		)
		(duplicate_pad_numbers_are_jumpers no)
		(fp_line
			(start -0.787516 0.406438)
			(end 0.787425 0.40652)
			(stroke
				(width 0.1524)
				(type default)
			)
			(layer "B.SilkS")
		)
		(fp_line
			(start -0.787425 -0.40652)
			(end -0.787516 0.406438)
			(stroke
				(width 0.1524)
				(type default)
			)
			(layer "B.SilkS")
		)
		(fp_line
			(start 0.787425 0.40652)
			(end 0.787516 -0.406438)
			(stroke
				(width 0.1524)
				(type default)
			)
			(layer "B.SilkS")
		)
		(fp_line
			(start 0.787516 -0.406438)
			(end -0.787425 -0.40652)
			(stroke
				(width 0.1524)
				(type default)
			)
			(layer "B.SilkS")
		)
		(fp_line
			(start -0.679568 0.304811)
			(end -0.120258 0.304812)
			(stroke
				(width 0.1)
				(type default)
			)
			(layer "B.Fab")
		)
		(fp_line
			(start -0.120258 0.304812)
			(end -0.120334 0.279545)
			(stroke
				(width 0.1)
				(type default)
			)
			(layer "B.Fab")
		)
		(fp_line
			(start -0.120334 0.279545)
			(end 0.120587 0.279326)
			(stroke
				(width 0.1)
				(type default)
			)
			(layer "B.Fab")
		)
		(fp_line
			(start 0.120536 0.304813)
			(end 0.6795 0.304908)
			(stroke
				(width 0.1)
				(type default)
			)
			(layer "B.Fab")
		)
		(fp_line
			(start 0.120587 0.279326)
			(end 0.120536 0.304813)
			(stroke
				(width 0.1)
				(type default)
			)
			(layer "B.Fab")
		)
		(fp_line
			(start -0.6795 -0.304908)
			(end -0.679568 0.304811)
			(stroke
				(width 0.1)
				(type default)
			)
			(layer "B.Fab")
		)
		(fp_line
			(start 0.6795 0.304908)
			(end 0.679475 -0.305158)
			(stroke
				(width 0.1)
				(type default)
			)
			(layer "B.Fab")
		)
		(fp_line
			(start -0.120587 -0.279326)
			(end -0.120536 -0.304813)
			(stroke
				(width 0.1)
				(type default)
			)
			(layer "B.Fab")
		)
		(fp_line
			(start -0.120536 -0.304813)
			(end -0.6795 -0.304908)
			(stroke
				(width 0.1)
				(type default)
			)
			(layer "B.Fab")
		)
		(fp_line
			(start 0.120554 -0.279418)
			(end -0.120587 -0.279326)
			(stroke
				(width 0.1)
				(type default)
			)
			(layer "B.Fab")
		)
		(fp_line
			(start 0.120732 -0.305125)
			(end 0.120554 -0.279418)
			(stroke
				(width 0.1)
				(type default)
			)
			(layer "B.Fab")
		)
		(fp_line
			(start 0.679475 -0.305158)
			(end 0.120732 -0.305125)
			(stroke
				(width 0.1)
				(type default)
			)
			(layer "B.Fab")
		)
		(pad "1" smd circle
			(at 0.40005 0 120)
			(size 0 0)
			(layers "B.Cu" "B.Mask" "B.Paste")
			(net "PVDDCR_SOC_P0")
		)
		(pad "2" smd circle
			(at -0.40005 0 120)
			(size 0 0)
			(layers "B.Cu" "B.Mask" "B.Paste")
			(net "GND")
		)
	)
)
